# S9S_MB_2U (Grand Teton) — schematic netlist excerpt (pin names and nets, part order shuffled) for the footprints in the layout excerpt that follows; sources: Cadence DE-HDL packaged netlist, KiCad conversion of 03242023_DA0F0TMBIJ0_F0T_Motherboard_J_brd_V01_OCP.brd

C1554  Q_CAP_DIFFBUS  DIFF BUS_0.22UF 6.3V 20% X6S  pkg C0201  page 175 : \1\ = P5E_CPU0_PE4_TX_C_DN<12> ; \2\ = P5E_CPU0_PE4_TX_DN<12>
R3170  Q_RES  0 5% CHIP  pkg 0402LF  page 159 : A = OCP_V3_2_ISO_BIF1_EN ; B = OCP_V3_2_BIF1_R_N
R1294  Q_RES  0 5% CHIP  pkg 0402LF  page 154 : A = NCSI_BMC_TX_EN_R ; B = RMII_BMC_OCP_TX_EN

(kicad_pcb
	(version 20260206)
	(generator "pcbnew")
	(generator_version "10.0")
	(general
		(thickness 1.6)
		(legacy_teardrops no)
	)
	(paper "A4")
	(title_block
		(title "03242023_DA0F0TMBIJ0_F0T_Motherboard_J_brd_V01_OCP.brd")
		(comment 1 "Grand Teton / footprints 3416-3418 of 6105")
	)
	(layers
		(0 "F.Cu" signal "TOP")
		(4 "In1.Cu" signal "GND")
		(6 "In2.Cu" signal "IN1")
		(8 "In3.Cu" signal "GND1")
		(10 "In4.Cu" signal "IN2")
		(12 "In5.Cu" signal "GND2")
		(14 "In6.Cu" signal "IN3")
		(16 "In7.Cu" signal "GND3")
		(18 "In8.Cu" signal "VCC")
		(20 "In9.Cu" signal "VCC1")
		(22 "In10.Cu" signal "GND4")
		(24 "In11.Cu" signal "IN4")
		(26 "In12.Cu" signal "GND5")
		(28 "In13.Cu" signal "IN5")
		(30 "In14.Cu" signal "GND6")
		(32 "In15.Cu" signal "IN6")
		(34 "In16.Cu" signal "GND7")
		(2 "B.Cu" signal "BOTTOM")
		(9 "F.Adhes" user "F.Adhesive")
		(11 "B.Adhes" user "B.Adhesive")
		(13 "F.Paste" user "Package Geometry/Pastemask Top")
		(15 "B.Paste" user "Package Geometry/Pastemask Bottom")
		(5 "F.SilkS" user "Ref Des/Silkscreen Top")
		(7 "B.SilkS" user "Ref Des/Silkscreen Bottom")
		(1 "F.Mask" user "Board Geometry/Soldermask Top")
		(3 "B.Mask" user "Board Geometry/Soldermask Bottom")
		(17 "Dwgs.User" user "User.Drawings")
		(19 "Cmts.User" user "User.Comments")
		(21 "Eco1.User" user "User.Eco1")
		(23 "Eco2.User" user "User.Eco2")
		(25 "Edge.Cuts" user "Board Geometry/Outline")
		(27 "Margin" user)
		(31 "F.CrtYd" user "Package Geometry/Place Bound Top")
		(29 "B.CrtYd" user "Package Geometry/Place Bound Bottom")
		(35 "F.Fab" user "Ref Des/Assembly Top")
		(33 "B.Fab" user "Ref Des/Assembly Bottom")
	)
	(footprint ""
		(layer "F.Cu")
		(at 62.28588 -16.220948 -90)
		(property "Reference" "R3170"
			(at 0 0 270)
			(layer "F.SilkS")
			(hide yes)
			(effects
				(font
					(size 1.27 1.27)
				)
			)
		)
		(property "Value" ""
			(at 0 0 270)
			(layer "F.Fab")
			(effects
				(font
					(size 1.27 1.27)
				)
			)
		)
		(duplicate_pad_numbers_are_jumpers no)
		(fp_line
			(start -0.7874 0.4064)
			(end -0.7874 -0.4064)
			(stroke
				(width 0.1524)
				(type default)
			)
			(layer "F.SilkS")
		)
		(fp_line
			(start 0.7874 0.4064)
			(end -0.7874 0.4064)
			(stroke
				(width 0.1524)
				(type default)
			)
			(layer "F.SilkS")
		)
		(fp_line
			(start -0.7874 -0.4064)
			(end 0.7874 -0.4064)
			(stroke
				(width 0.1524)
				(type default)
			)
			(layer "F.SilkS")
		)
		(fp_line
			(start 0.7874 -0.4064)
			(end 0.7874 0.4064)
			(stroke
				(width 0.1524)
				(type default)
			)
			(layer "F.SilkS")
		)
		(fp_line
			(start -0.67945 0.3048)
			(end -0.67945 -0.305054)
			(stroke
				(width 0.1)
				(type default)
			)
			(layer "F.Fab")
		)
		(fp_line
			(start -0.12065 0.3048)
			(end -0.67945 0.3048)
			(stroke
				(width 0.1)
				(type default)
			)
			(layer "F.Fab")
		)
		(fp_line
			(start 0.120396 0.3048)
			(end 0.120396 0.2794)
			(stroke
				(width 0.1)
				(type default)
			)
			(layer "F.Fab")
		)
		(fp_line
			(start 0.67945 0.3048)
			(end 0.120396 0.3048)
			(stroke
				(width 0.1)
				(type default)
			)
			(layer "F.Fab")
		)
		(fp_line
			(start -0.12065 0.2794)
			(end -0.12065 0.3048)
			(stroke
				(width 0.1)
				(type default)
			)
			(layer "F.Fab")
		)
		(fp_line
			(start 0.120396 0.2794)
			(end -0.12065 0.2794)
			(stroke
				(width 0.1)
				(type default)
			)
			(layer "F.Fab")
		)
		(fp_line
			(start -0.12065 -0.2794)
			(end 0.12065 -0.2794)
			(stroke
				(width 0.1)
				(type default)
			)
			(layer "F.Fab")
		)
		(fp_line
			(start 0.12065 -0.2794)
			(end 0.12065 -0.3048)
			(stroke
				(width 0.1)
				(type default)
			)
			(layer "F.Fab")
		)
		(fp_line
			(start 0.12065 -0.3048)
			(end 0.67945 -0.3048)
			(stroke
				(width 0.1)
				(type default)
			)
			(layer "F.Fab")
		)
		(fp_line
			(start 0.67945 -0.3048)
			(end 0.67945 0.3048)
			(stroke
				(width 0.1)
				(type default)
			)
			(layer "F.Fab")
		)
		(fp_line
			(start -0.67945 -0.305054)
			(end -0.12065 -0.305054)
			(stroke
				(width 0.1)
				(type default)
			)
			(layer "F.Fab")
		)
		(fp_line
			(start -0.12065 -0.305054)
			(end -0.12065 -0.2794)
			(stroke
				(width 0.1)
				(type default)
			)
			(layer "F.Fab")
		)
		(pad "1" smd circle
			(at -0.40005 0 270)
			(size 0 0)
			(layers "F.Cu" "F.Mask" "F.Paste")
			(net "OCP_V3_2_ISO_BIF1_EN")
		)
		(pad "2" smd circle
			(at 0.40005 0 270)
			(size 0 0)
			(layers "F.Cu" "F.Mask" "F.Paste")
			(net "OCP_V3_2_BIF1_R_N")
		)
	)
	(footprint ""
		(layer "F.Cu")
		(at 214.75827 -72.641714 90)
		(property "Reference" "R1294"
			(at 0 0 90)
			(layer "F.SilkS")
			(hide yes)
			(effects
				(font
					(size 1.27 1.27)
				)
			)
		)
		(property "Value" ""
			(at 0 0 90)
			(layer "F.Fab")
			(effects
				(font
					(size 1.27 1.27)
				)
			)
		)
		(duplicate_pad_numbers_are_jumpers no)
		(fp_line
			(start 0.7874 -0.4064)
			(end 0.7874 0.4064)
			(stroke
				(width 0.1524)
				(type default)
			)
			(layer "F.SilkS")
		)
		(fp_line
			(start -0.7874 -0.4064)
			(end 0.7874 -0.4064)
			(stroke
				(width 0.1524)
				(type default)
			)
			(layer "F.SilkS")
		)
		(fp_line
			(start 0.7874 0.4064)
			(end -0.7874 0.4064)
			(stroke
				(width 0.1524)
				(type default)
			)
			(layer "F.SilkS")
		)
		(fp_line
			(start -0.7874 0.4064)
			(end -0.7874 -0.4064)
			(stroke
				(width 0.1524)
				(type default)
			)
			(layer "F.SilkS")
		)
		(fp_line
			(start -0.12065 -0.305054)
			(end -0.12065 -0.2794)
			(stroke
				(width 0.1)
				(type default)
			)
			(layer "F.Fab")
		)
		(fp_line
			(start -0.67945 -0.305054)
			(end -0.12065 -0.305054)
			(stroke
				(width 0.1)
				(type default)
			)
			(layer "F.Fab")
		)
		(fp_line
			(start 0.67945 -0.3048)
			(end 0.67945 0.3048)
			(stroke
				(width 0.1)
				(type default)
			)
			(layer "F.Fab")
		)
		(fp_line
			(start 0.12065 -0.3048)
			(end 0.67945 -0.3048)
			(stroke
				(width 0.1)
				(type default)
			)
			(layer "F.Fab")
		)
		(fp_line
			(start 0.12065 -0.2794)
			(end 0.12065 -0.3048)
			(stroke
				(width 0.1)
				(type default)
			)
			(layer "F.Fab")
		)
		(fp_line
			(start -0.12065 -0.2794)
			(end 0.12065 -0.2794)
			(stroke
				(width 0.1)
				(type default)
			)
			(layer "F.Fab")
		)
		(fp_line
			(start 0.120396 0.2794)
			(end -0.12065 0.2794)
			(stroke
				(width 0.1)
				(type default)
			)
			(layer "F.Fab")
		)
		(fp_line
			(start -0.12065 0.2794)
			(end -0.12065 0.3048)
			(stroke
				(width 0.1)
				(type default)
			)
			(layer "F.Fab")
		)
		(fp_line
			(start 0.67945 0.3048)
			(end 0.120396 0.3048)
			(stroke
				(width 0.1)
				(type default)
			)
			(layer "F.Fab")
		)
		(fp_line
			(start 0.120396 0.3048)
			(end 0.120396 0.2794)
			(stroke
				(width 0.1)
				(type default)
			)
			(layer "F.Fab")
		)
		(fp_line
			(start -0.12065 0.3048)
			(end -0.67945 0.3048)
			(stroke
				(width 0.1)
				(type default)
			)
			(layer "F.Fab")
		)
		(fp_line
			(start -0.67945 0.3048)
			(end -0.67945 -0.305054)
			(stroke
				(width 0.1)
				(type default)
			)
			(layer "F.Fab")
		)
		(pad "1" smd circle
			(at -0.40005 0 90)
			(size 0 0)
			(layers "F.Cu" "F.Mask" "F.Paste")
			(net "NCSI_BMC_TX_EN_R")
		)
		(pad "2" smd circle
			(at 0.40005 0 90)
			(size 0 0)
			(layers "F.Cu" "F.Mask" "F.Paste")
			(net "RMII_BMC_OCP_TX_EN")
		)
	)
	(footprint ""
		(layer "F.Cu")
		(at 340.713568 -402.371052 -90)
		(property "Reference" "C1554"
			(at 0 0 270)
			(layer "F.SilkS")
			(hide yes)
			(effects
				(font
					(size 1.27 1.27)
				)
			)
		)
		(property "Value" ""
			(at 0 0 270)
			(layer "F.Fab")
			(effects
				(font
					(size 1.27 1.27)
				)
			)
		)
		(duplicate_pad_numbers_are_jumpers no)
		(fp_line
			(start -0.299974 0.150114)
			(end -0.299974 -0.150114)
			(stroke
				(width 0.1)
				(type default)
			)
			(layer "F.Fab")
		)
		(fp_line
			(start 0.299974 0.150114)
			(end -0.299974 0.150114)
			(stroke
				(width 0.1)
				(type default)
			)
			(layer "F.Fab")
		)
		(fp_line
			(start -0.299974 -0.150114)
			(end 0.299974 -0.150114)
			(stroke
				(width 0.1)
				(type default)
			)
			(layer "F.Fab")
		)
		(fp_line
			(start 0.299974 -0.150114)
			(end 0.299974 0.150114)
			(stroke
				(width 0.1)
				(type default)
			)
			(layer "F.Fab")
		)
		(pad "1" smd rect
			(at -0.2667 0 270)
			(size 0.3048 0.381)
			(layers "F.Cu" "F.Mask" "F.Paste")
			(net "P5E_CPU0_PE4_TX_C_DN<12>")
		)
		(pad "2" smd rect
			(at 0.2667 0 270)
			(size 0.3048 0.381)
			(layers "F.Cu" "F.Mask" "F.Paste")
			(net "P5E_CPU0_PE4_TX_DN<12>")
		)
	)
)
